# T6G (Grand Teton) — schematic netlist excerpt (pin names and nets, part order shuffled) for the footprints in the layout excerpt that follows; sources: Cadence DE-HDL packaged netlist, KiCad conversion of 04192023_DAF0TMB3IC0_F0TG_MB_C_brd_V02_OCP.brd

J115  PICOPROBE_BXA  DELTA-L 4.0 EMPTY  pkg TRIANG_LAUNCH_3PXB  page 229
  \1_p\  = DELTA_L_85_5INCH_IN6_DP
  \2_n\  = DELTA_L_85_5INCH_IN6_DN
  \3_g\  = DELTA_L_GND_1

R1067  Q_RES  0 5% CHIP  pkg 0201LF  page 298 : A = SMB_RT_CPU0_P2_R_SCL ; B = SMB_RT_CPU0_P2_R2_SCL

(kicad_pcb
	(version 20260206)
	(generator "pcbnew")
	(generator_version "10.0")
	(general
		(thickness 1.6)
		(legacy_teardrops no)
	)
	(paper "A4")
	(title_block
		(title "04192023_DAF0TMB3IC0_F0TG_MB_C_brd_V02_OCP.brd")
		(comment 1 "Grand Teton / footprints 5744-5745 of 8354")
	)
	(layers
		(0 "F.Cu" signal "TOP")
		(4 "In1.Cu" signal "GND")
		(6 "In2.Cu" signal "IN1")
		(8 "In3.Cu" signal "GND1")
		(10 "In4.Cu" signal "IN2")
		(12 "In5.Cu" signal "GND2")
		(14 "In6.Cu" signal "IN3")
		(16 "In7.Cu" signal "GND3")
		(18 "In8.Cu" signal "VCC")
		(20 "In9.Cu" signal "VCC1")
		(22 "In10.Cu" signal "GND4")
		(24 "In11.Cu" signal "IN4")
		(26 "In12.Cu" signal "GND5")
		(28 "In13.Cu" signal "IN5")
		(30 "In14.Cu" signal "GND6")
		(32 "In15.Cu" signal "IN6")
		(34 "In16.Cu" signal "GND7")
		(2 "B.Cu" signal "BOTTOM")
		(9 "F.Adhes" user "F.Adhesive")
		(11 "B.Adhes" user "B.Adhesive")
		(13 "F.Paste" user "Package Geometry/Pastemask Top")
		(15 "B.Paste" user "Package Geometry/Pastemask Bottom")
		(5 "F.SilkS" user "Ref Des/Silkscreen Top")
		(7 "B.SilkS" user "Ref Des/Silkscreen Bottom")
		(1 "F.Mask" user "Board Geometry/Soldermask Top")
		(3 "B.Mask" user "Board Geometry/Soldermask Bottom")
		(17 "Dwgs.User" user "User.Drawings")
		(19 "Cmts.User" user "User.Comments")
		(21 "Eco1.User" user "User.Eco1")
		(23 "Eco2.User" user "User.Eco2")
		(25 "Edge.Cuts" user "Board Geometry/Outline")
		(27 "Margin" user)
		(31 "F.CrtYd" user "Package Geometry/Place Bound Top")
		(29 "B.CrtYd" user "Package Geometry/Place Bound Bottom")
		(35 "F.Fab" user "Ref Des/Assembly Top")
		(33 "B.Fab" user "Ref Des/Assembly Bottom")
	)
	(footprint ""
		(layer "B.Cu")
		(at 314.965588 -2.537206 180)
		(property "Reference" "J115"
			(at 4.61264 -1.551178 270)
			(unlocked yes)
			(layer "B.SilkS")
			(effects
				(font
					(size 0.7874 0.5842)
					(thickness 0.1524)
				)
				(justify left mirror)
			)
		)
		(property "Value" ""
			(at 0 0 0)
			(layer "B.Fab")
			(effects
				(font
					(size 1.27 1.27)
				)
				(justify mirror)
			)
		)
		(duplicate_pad_numbers_are_jumpers no)
		(fp_line
			(start 1.2192 2.06756)
			(end 1.2192 -2.06756)
			(stroke
				(width 0.1524)
				(type default)
			)
			(layer "B.SilkS")
		)
		(fp_line
			(start 1.2192 -2.06756)
			(end -1.2192 -2.06756)
			(stroke
				(width 0.1524)
				(type default)
			)
			(layer "B.SilkS")
		)
		(fp_line
			(start -1.2192 2.06756)
			(end 1.2192 2.06756)
			(stroke
				(width 0.1524)
				(type default)
			)
			(layer "B.SilkS")
		)
		(fp_line
			(start -1.2192 -2.06756)
			(end -1.2192 2.06756)
			(stroke
				(width 0.1524)
				(type default)
			)
			(layer "B.SilkS")
		)
		(pad "" np_thru_hole circle
			(at -3.4671 -1.27 90)
			(size 1.0414 1.0414)
			(drill 1.0414)
			(layers "*.Cu" "*.Mask")
			(clearance 0.381)
			(thermal_gap 0.381)
		)
		(pad "" np_thru_hole circle
			(at -3.4671 1.27 90)
			(size 1.0414 1.0414)
			(drill 1.0414)
			(layers "*.Cu" "*.Mask")
			(clearance 0.381)
			(thermal_gap 0.381)
		)
		(pad "" np_thru_hole circle
			(at 2.8829 -1.27 90)
			(size 1.0414 1.0414)
			(drill 1.0414)
			(layers "*.Cu" "*.Mask")
			(clearance 0.381)
			(thermal_gap 0.381)
		)
		(pad "" np_thru_hole circle
			(at 2.8829 1.27 90)
			(size 1.0414 1.0414)
			(drill 1.0414)
			(layers "*.Cu" "*.Mask")
			(clearance 0.381)
			(thermal_gap 0.381)
		)
		(pad "1" smd rect
			(at -0.8255 -0.249936 90)
			(size 0.3048 0.508)
			(layers "B.Cu" "B.Mask" "B.Paste")
			(net "DELTA_L_85_5INCH_IN6_DP")
		)
		(pad "2" smd rect
			(at -0.8255 0.249936 90)
			(size 0.3048 0.508)
			(layers "B.Cu" "B.Mask" "B.Paste")
			(net "DELTA_L_85_5INCH_IN6_DN")
		)
		(pad "3" smd circle
			(at 0 0)
			(size 0 0)
			(layers "B.Cu" "B.Mask" "B.Paste")
			(net "DELTA_L_GND_1")
		)
		(zone
			(layers "F.Cu" "B.Cu" "In1.Cu" "In2.Cu" "In3.Cu" "In4.Cu" "In5.Cu" "In6.Cu"
				"In7.Cu" "In8.Cu" "In9.Cu" "In10.Cu" "In11.Cu" "In12.Cu" "In13.Cu" "In14.Cu"
				"In15.Cu" "In16.Cu"
			)
			(hatch none 0.5)
			(connect_pads
				(clearance 0)
			)
			(min_thickness 0.25)
			(keepout
				(tracks not_allowed)
				(vias allowed)
				(pads allowed)
				(copperpour not_allowed)
				(footprints allowed)
			)
			(placement
				(enabled no)
				(sheetname "")
			)
			(fill
				(thermal_gap 0.5)
				(thermal_bridge_width 0.5)
				(island_removal_mode 0)
			)
			(polygon
				(pts
					(arc
						(start 313.009788 -3.807206)
						(mid 311.155588 -3.807206)
						(end 313.009788 -3.807206)
					)
				)
			)
		)
		(zone
			(layers "F.Cu" "B.Cu" "In1.Cu" "In2.Cu" "In3.Cu" "In4.Cu" "In5.Cu" "In6.Cu"
				"In7.Cu" "In8.Cu" "In9.Cu" "In10.Cu" "In11.Cu" "In12.Cu" "In13.Cu" "In14.Cu"
				"In15.Cu" "In16.Cu"
			)
			(hatch none 0.5)
			(connect_pads
				(clearance 0)
			)
			(min_thickness 0.25)
			(keepout
				(tracks not_allowed)
				(vias allowed)
				(pads allowed)
				(copperpour not_allowed)
				(footprints allowed)
			)
			(placement
				(enabled no)
				(sheetname "")
			)
			(fill
				(thermal_gap 0.5)
				(thermal_bridge_width 0.5)
				(island_removal_mode 0)
			)
			(polygon
				(pts
					(arc
						(start 313.009788 -1.267206)
						(mid 311.155588 -1.267206)
						(end 313.009788 -1.267206)
					)
				)
			)
		)
		(zone
			(layers "F.Cu" "B.Cu" "In1.Cu" "In2.Cu" "In3.Cu" "In4.Cu" "In5.Cu" "In6.Cu"
				"In7.Cu" "In8.Cu" "In9.Cu" "In10.Cu" "In11.Cu" "In12.Cu" "In13.Cu" "In14.Cu"
				"In15.Cu" "In16.Cu"
			)
			(hatch none 0.5)
			(connect_pads
				(clearance 0)
			)
			(min_thickness 0.25)
			(keepout
				(tracks not_allowed)
				(vias allowed)
				(pads allowed)
				(copperpour not_allowed)
				(footprints allowed)
			)
			(placement
				(enabled no)
				(sheetname "")
			)
			(fill
				(thermal_gap 0.5)
				(thermal_bridge_width 0.5)
				(island_removal_mode 0)
			)
			(polygon
				(pts
					(arc
						(start 319.359788 -3.807206)
						(mid 317.505588 -3.807206)
						(end 319.359788 -3.807206)
					)
				)
			)
		)
		(zone
			(layers "F.Cu" "B.Cu" "In1.Cu" "In2.Cu" "In3.Cu" "In4.Cu" "In5.Cu" "In6.Cu"
				"In7.Cu" "In8.Cu" "In9.Cu" "In10.Cu" "In11.Cu" "In12.Cu" "In13.Cu" "In14.Cu"
				"In15.Cu" "In16.Cu"
			)
			(hatch none 0.5)
			(connect_pads
				(clearance 0)
			)
			(min_thickness 0.25)
			(keepout
				(tracks not_allowed)
				(vias allowed)
				(pads allowed)
				(copperpour not_allowed)
				(footprints allowed)
			)
			(placement
				(enabled no)
				(sheetname "")
			)
			(fill
				(thermal_gap 0.5)
				(thermal_bridge_width 0.5)
				(island_removal_mode 0)
			)
			(polygon
				(pts
					(arc
						(start 319.359788 -1.267206)
						(mid 317.505588 -1.267206)
						(end 319.359788 -1.267206)
					)
				)
			)
		)
		(zone
			(layer "B.Cu")
			(hatch none 0.5)
			(connect_pads
				(clearance 0)
			)
			(min_thickness 0.25)
			(keepout
				(tracks not_allowed)
				(vias allowed)
				(pads allowed)
				(copperpour not_allowed)
				(footprints allowed)
			)
			(placement
				(enabled no)
				(sheetname "")
			)
			(fill
				(thermal_gap 0.5)
				(thermal_bridge_width 0.5)
				(island_removal_mode 0)
			)
			(polygon
				(pts
					(xy 316.083188 -1.988566) (xy 316.083188 -2.08407) (xy 315.486288 -2.08407) (xy 315.486288 -2.49047)
					(xy 316.083188 -2.49047) (xy 316.083188 -2.583942) (xy 315.486288 -2.583942) (xy 315.486288 -2.990342)
					(xy 316.083188 -2.990342) (xy 316.083188 -3.085846) (xy 315.384688 -3.085846) (xy 315.384688 -1.988566)
				)
			)
		)
	)
	(footprint ""
		(layer "B.Cu")
		(at 233.807 -334.01 180)
		(property "Reference" "R1067"
			(at 0 0 0)
			(layer "B.SilkS")
			(hide yes)
			(effects
				(font
					(size 1.27 1.27)
				)
				(justify mirror)
			)
		)
		(property "Value" ""
			(at 0 0 0)
			(layer "B.Fab")
			(effects
				(font
					(size 1.27 1.27)
				)
				(justify mirror)
			)
		)
		(duplicate_pad_numbers_are_jumpers no)
		(fp_line
			(start 0.32512 0.175006)
			(end 0.32512 -0.175006)
			(stroke
				(width 0.1)
				(type default)
			)
			(layer "B.Fab")
		)
		(fp_line
			(start 0.32512 -0.175006)
			(end -0.32512 -0.175006)
			(stroke
				(width 0.1)
				(type default)
			)
			(layer "B.Fab")
		)
		(fp_line
			(start -0.32512 0.175006)
			(end 0.32512 0.175006)
			(stroke
				(width 0.1)
				(type default)
			)
			(layer "B.Fab")
		)
		(fp_line
			(start -0.32512 -0.175006)
			(end -0.32512 0.175006)
			(stroke
				(width 0.1)
				(type default)
			)
			(layer "B.Fab")
		)
		(pad "1" smd rect
			(at 0.2667 0)
			(size 0.3048 0.381)
			(layers "B.Cu" "B.Mask" "B.Paste")
			(net "SMB_RT_CPU0_P2_R_SCL")
		)
		(pad "2" smd rect
			(at -0.2667 0 180)
			(size 0.3048 0.381)
			(layers "B.Cu" "B.Mask" "B.Paste")
			(net "SMB_RT_CPU0_P2_R2_SCL")
		)
	)
)
